# S9S_MB_2U (Grand Teton) — schematic netlist excerpt (pin names and nets, part order shuffled) for the footprints in the layout excerpt that follows; sources: Cadence DE-HDL packaged netlist, KiCad conversion of 03242023_DA0F0TMBIJ0_F0T_Motherboard_J_brd_V01_OCP.brd

R3335  Q_RES  0 5% CHIP  pkg 0402LF  page 212 : A = CLK_100M_BMC_RC_DP_R ; B = CLK_100M_BMC_RC_DP
R4066  Q_RES  4.7K 5% CHIP  pkg 0402LF  page 162 : A = P3V3_OCP_EN_2_R ; B = GND

(kicad_pcb
	(version 20260206)
	(generator "pcbnew")
	(generator_version "10.0")
	(general
		(thickness 1.6)
		(legacy_teardrops no)
	)
	(paper "A4")
	(title_block
		(title "03242023_DA0F0TMBIJ0_F0T_Motherboard_J_brd_V01_OCP.brd")
		(comment 1 "Grand Teton / footprints 2592-2593 of 6105")
	)
	(layers
		(0 "F.Cu" signal "TOP")
		(4 "In1.Cu" signal "GND")
		(6 "In2.Cu" signal "IN1")
		(8 "In3.Cu" signal "GND1")
		(10 "In4.Cu" signal "IN2")
		(12 "In5.Cu" signal "GND2")
		(14 "In6.Cu" signal "IN3")
		(16 "In7.Cu" signal "GND3")
		(18 "In8.Cu" signal "VCC")
		(20 "In9.Cu" signal "VCC1")
		(22 "In10.Cu" signal "GND4")
		(24 "In11.Cu" signal "IN4")
		(26 "In12.Cu" signal "GND5")
		(28 "In13.Cu" signal "IN5")
		(30 "In14.Cu" signal "GND6")
		(32 "In15.Cu" signal "IN6")
		(34 "In16.Cu" signal "GND7")
		(2 "B.Cu" signal "BOTTOM")
		(9 "F.Adhes" user "F.Adhesive")
		(11 "B.Adhes" user "B.Adhesive")
		(13 "F.Paste" user "Package Geometry/Pastemask Top")
		(15 "B.Paste" user "Package Geometry/Pastemask Bottom")
		(5 "F.SilkS" user "Ref Des/Silkscreen Top")
		(7 "B.SilkS" user "Ref Des/Silkscreen Bottom")
		(1 "F.Mask" user "Board Geometry/Soldermask Top")
		(3 "B.Mask" user "Board Geometry/Soldermask Bottom")
		(17 "Dwgs.User" user "User.Drawings")
		(19 "Cmts.User" user "User.Comments")
		(21 "Eco1.User" user "User.Eco1")
		(23 "Eco2.User" user "User.Eco2")
		(25 "Edge.Cuts" user "Board Geometry/Outline")
		(27 "Margin" user)
		(31 "F.CrtYd" user "Package Geometry/Place Bound Top")
		(29 "B.CrtYd" user "Package Geometry/Place Bound Bottom")
		(35 "F.Fab" user "Ref Des/Assembly Top")
		(33 "B.Fab" user "Ref Des/Assembly Bottom")
	)
	(footprint ""
		(layer "F.Cu")
		(at 58.93308 -40.404034 180)
		(property "Reference" "R4066"
			(at 0 0 180)
			(layer "F.SilkS")
			(hide yes)
			(effects
				(font
					(size 1.27 1.27)
				)
			)
		)
		(property "Value" ""
			(at 0 0 180)
			(layer "F.Fab")
			(effects
				(font
					(size 1.27 1.27)
				)
			)
		)
		(duplicate_pad_numbers_are_jumpers no)
		(fp_line
			(start 0.7874 0.4064)
			(end -0.7874 0.4064)
			(stroke
				(width 0.1524)
				(type default)
			)
			(layer "F.SilkS")
		)
		(fp_line
			(start 0.7874 -0.4064)
			(end 0.7874 0.4064)
			(stroke
				(width 0.1524)
				(type default)
			)
			(layer "F.SilkS")
		)
		(fp_line
			(start -0.7874 0.4064)
			(end -0.7874 -0.4064)
			(stroke
				(width 0.1524)
				(type default)
			)
			(layer "F.SilkS")
		)
		(fp_line
			(start -0.7874 -0.4064)
			(end 0.7874 -0.4064)
			(stroke
				(width 0.1524)
				(type default)
			)
			(layer "F.SilkS")
		)
		(fp_line
			(start 0.67945 0.3048)
			(end 0.120396 0.3048)
			(stroke
				(width 0.1)
				(type default)
			)
			(layer "F.Fab")
		)
		(fp_line
			(start 0.67945 -0.3048)
			(end 0.67945 0.3048)
			(stroke
				(width 0.1)
				(type default)
			)
			(layer "F.Fab")
		)
		(fp_line
			(start 0.12065 -0.2794)
			(end 0.12065 -0.3048)
			(stroke
				(width 0.1)
				(type default)
			)
			(layer "F.Fab")
		)
		(fp_line
			(start 0.12065 -0.3048)
			(end 0.67945 -0.3048)
			(stroke
				(width 0.1)
				(type default)
			)
			(layer "F.Fab")
		)
		(fp_line
			(start 0.120396 0.3048)
			(end 0.120396 0.2794)
			(stroke
				(width 0.1)
				(type default)
			)
			(layer "F.Fab")
		)
		(fp_line
			(start 0.120396 0.2794)
			(end -0.12065 0.2794)
			(stroke
				(width 0.1)
				(type default)
			)
			(layer "F.Fab")
		)
		(fp_line
			(start -0.12065 0.3048)
			(end -0.67945 0.3048)
			(stroke
				(width 0.1)
				(type default)
			)
			(layer "F.Fab")
		)
		(fp_line
			(start -0.12065 0.2794)
			(end -0.12065 0.3048)
			(stroke
				(width 0.1)
				(type default)
			)
			(layer "F.Fab")
		)
		(fp_line
			(start -0.12065 -0.2794)
			(end 0.12065 -0.2794)
			(stroke
				(width 0.1)
				(type default)
			)
			(layer "F.Fab")
		)
		(fp_line
			(start -0.12065 -0.305054)
			(end -0.12065 -0.2794)
			(stroke
				(width 0.1)
				(type default)
			)
			(layer "F.Fab")
		)
		(fp_line
			(start -0.67945 0.3048)
			(end -0.67945 -0.305054)
			(stroke
				(width 0.1)
				(type default)
			)
			(layer "F.Fab")
		)
		(fp_line
			(start -0.67945 -0.305054)
			(end -0.12065 -0.305054)
			(stroke
				(width 0.1)
				(type default)
			)
			(layer "F.Fab")
		)
		(pad "1" smd circle
			(at -0.40005 0 180)
			(size 0 0)
			(layers "F.Cu" "F.Mask" "F.Paste")
			(net "P3V3_OCP_EN_2_R")
		)
		(pad "2" smd circle
			(at 0.40005 0 180)
			(size 0 0)
			(layers "F.Cu" "F.Mask" "F.Paste")
			(net "GND")
		)
	)
	(footprint ""
		(layer "F.Cu")
		(at 230.248206 -252.179836 180)
		(property "Reference" "R3335"
			(at 0 0 180)
			(layer "F.SilkS")
			(hide yes)
			(effects
				(font
					(size 1.27 1.27)
				)
			)
		)
		(property "Value" ""
			(at 0 0 180)
			(layer "F.Fab")
			(effects
				(font
					(size 1.27 1.27)
				)
			)
		)
		(duplicate_pad_numbers_are_jumpers no)
		(fp_line
			(start 0.7874 0.4064)
			(end -0.7874 0.4064)
			(stroke
				(width 0.1524)
				(type default)
			)
			(layer "F.SilkS")
		)
		(fp_line
			(start 0.7874 -0.4064)
			(end 0.7874 0.4064)
			(stroke
				(width 0.1524)
				(type default)
			)
			(layer "F.SilkS")
		)
		(fp_line
			(start -0.7874 0.4064)
			(end -0.7874 -0.4064)
			(stroke
				(width 0.1524)
				(type default)
			)
			(layer "F.SilkS")
		)
		(fp_line
			(start -0.7874 -0.4064)
			(end 0.7874 -0.4064)
			(stroke
				(width 0.1524)
				(type default)
			)
			(layer "F.SilkS")
		)
		(fp_line
			(start 0.67945 0.3048)
			(end 0.120396 0.3048)
			(stroke
				(width 0.1)
				(type default)
			)
			(layer "F.Fab")
		)
		(fp_line
			(start 0.67945 -0.3048)
			(end 0.67945 0.3048)
			(stroke
				(width 0.1)
				(type default)
			)
			(layer "F.Fab")
		)
		(fp_line
			(start 0.12065 -0.2794)
			(end 0.12065 -0.3048)
			(stroke
				(width 0.1)
				(type default)
			)
			(layer "F.Fab")
		)
		(fp_line
			(start 0.12065 -0.3048)
			(end 0.67945 -0.3048)
			(stroke
				(width 0.1)
				(type default)
			)
			(layer "F.Fab")
		)
		(fp_line
			(start 0.120396 0.3048)
			(end 0.120396 0.2794)
			(stroke
				(width 0.1)
				(type default)
			)
			(layer "F.Fab")
		)
		(fp_line
			(start 0.120396 0.2794)
			(end -0.12065 0.2794)
			(stroke
				(width 0.1)
				(type default)
			)
			(layer "F.Fab")
		)
		(fp_line
			(start -0.12065 0.3048)
			(end -0.67945 0.3048)
			(stroke
				(width 0.1)
				(type default)
			)
			(layer "F.Fab")
		)
		(fp_line
			(start -0.12065 0.2794)
			(end -0.12065 0.3048)
			(stroke
				(width 0.1)
				(type default)
			)
			(layer "F.Fab")
		)
		(fp_line
			(start -0.12065 -0.2794)
			(end 0.12065 -0.2794)
			(stroke
				(width 0.1)
				(type default)
			)
			(layer "F.Fab")
		)
		(fp_line
			(start -0.12065 -0.305054)
			(end -0.12065 -0.2794)
			(stroke
				(width 0.1)
				(type default)
			)
			(layer "F.Fab")
		)
		(fp_line
			(start -0.67945 0.3048)
			(end -0.67945 -0.305054)
			(stroke
				(width 0.1)
				(type default)
			)
			(layer "F.Fab")
		)
		(fp_line
			(start -0.67945 -0.305054)
			(end -0.12065 -0.305054)
			(stroke
				(width 0.1)
				(type default)
			)
			(layer "F.Fab")
		)
		(pad "1" smd circle
			(at -0.40005 0 180)
			(size 0 0)
			(layers "F.Cu" "F.Mask" "F.Paste")
			(net "CLK_100M_BMC_RC_DP_R")
		)
		(pad "2" smd circle
			(at 0.40005 0 180)
			(size 0 0)
			(layers "F.Cu" "F.Mask" "F.Paste")
			(net "CLK_100M_BMC_RC_DP")
		)
	)
)
